(kicad_pcb
	(version 20260206)
	(generator "pcbnew")
	(generator_version "10.0")
	(general
		(thickness 1.6)
		(legacy_teardrops no)
	)
	(paper "A4")
	(title_block
		(title "04192023_DAF0TMB3IC0_F0TG_MB_C_brd_V02_OCP.brd")
		(comment 1 "Grand Teton / footprint 3955 of 8354 (U25), pads 5886-5998 of 6102")
	)
	(layers
		(0 "F.Cu" signal "TOP")
		(4 "In1.Cu" signal "GND")
		(6 "In2.Cu" signal "IN1")
		(8 "In3.Cu" signal "GND1")
		(10 "In4.Cu" signal "IN2")
		(12 "In5.Cu" signal "GND2")
		(14 "In6.Cu" signal "IN3")
		(16 "In7.Cu" signal "GND3")
		(18 "In8.Cu" signal "VCC")
		(20 "In9.Cu" signal "VCC1")
		(22 "In10.Cu" signal "GND4")
		(24 "In11.Cu" signal "IN4")
		(26 "In12.Cu" signal "GND5")
		(28 "In13.Cu" signal "IN5")
		(30 "In14.Cu" signal "GND6")
		(32 "In15.Cu" signal "IN6")
		(34 "In16.Cu" signal "GND7")
		(2 "B.Cu" signal "BOTTOM")
		(9 "F.Adhes" user "F.Adhesive")
		(11 "B.Adhes" user "B.Adhesive")
		(13 "F.Paste" user "Package Geometry/Pastemask Top")
		(15 "B.Paste" user "Package Geometry/Pastemask Bottom")
		(5 "F.SilkS" user "Ref Des/Silkscreen Top")
		(7 "B.SilkS" user "Ref Des/Silkscreen Bottom")
		(1 "F.Mask" user "Board Geometry/Soldermask Top")
		(3 "B.Mask" user "Board Geometry/Soldermask Bottom")
		(17 "Dwgs.User" user "User.Drawings")
		(19 "Cmts.User" user "User.Comments")
		(21 "Eco1.User" user "User.Eco1")
		(23 "Eco2.User" user "User.Eco2")
		(25 "Edge.Cuts" user "Board Geometry/Outline")
		(27 "Margin" user)
		(31 "F.CrtYd" user "Package Geometry/Place Bound Top")
		(29 "B.CrtYd" user "Package Geometry/Place Bound Bottom")
		(35 "F.Fab" user "Ref Des/Assembly Top")
		(33 "B.Fab" user "Ref Des/Assembly Bottom")
	)
	(footprint ""
		(layer "F.Cu")
		(at 359.867962 -258.880102 180)
		(property "Reference" "U25"
			(at -45.78477 -62.086744 0)
			(unlocked yes)
			(layer "F.SilkS")
			(effects
				(font
					(size 0.7874 0.5842)
					(thickness 0.1524)
				)
			)
		)
		(property "Value" ""
			(at 0 0 180)
			(layer "F.Fab")
			(effects
				(font
					(size 1.27 1.27)
				)
			)
		)
		(duplicate_pad_numbers_are_jumpers no)
		(pad "U75" smd circle
			(at 34.459926 -23.850092 180)
			(size 0.450088 0.450088)
			(layers "F.Cu" "F.Mask" "F.Paste")
			(net "GND")
		)
		(pad "V2" smd circle
			(at -33.690052 -23.040086 180)
			(size 0.450088 0.450088)
			(layers "F.Cu" "F.Mask" "F.Paste")
			(net "M_G_CPU0_SA_DQ<18>")
		)
		(pad "V3" smd circle
			(at -32.749998 -23.040086 180)
			(size 0.450088 0.450088)
			(layers "F.Cu" "F.Mask" "F.Paste")
			(net "GND")
		)
		(pad "V4" smd circle
			(at -31.809944 -23.040086 180)
			(size 0.450088 0.450088)
			(layers "F.Cu" "F.Mask" "F.Paste")
			(net "M_G_CPU0_SA_DQ<17>")
		)
		(pad "V5" smd circle
			(at -30.86989 -23.040086 180)
			(size 0.450088 0.450088)
			(layers "F.Cu" "F.Mask" "F.Paste")
			(net "GND")
		)
		(pad "V6" smd circle
			(at -29.93009 -23.040086 180)
			(size 0.450088 0.450088)
			(layers "F.Cu" "F.Mask" "F.Paste")
			(net "M_K_CPU0_SA_DQ<18>")
		)
		(pad "V7" smd circle
			(at -28.990036 -23.040086 180)
			(size 0.450088 0.450088)
			(layers "F.Cu" "F.Mask" "F.Paste")
			(net "M_K_CPU0_SA_DQ<17>")
		)
		(pad "V8" smd circle
			(at -28.049982 -23.040086 180)
			(size 0.450088 0.450088)
			(layers "F.Cu" "F.Mask" "F.Paste")
			(net "GND")
		)
		(pad "V9" smd circle
			(at -27.109928 -23.040086 180)
			(size 0.450088 0.450088)
			(layers "F.Cu" "F.Mask" "F.Paste")
			(net "M_L_CPU0_SA_DQ<18>")
		)
		(pad "V10" smd circle
			(at -26.170128 -23.040086 180)
			(size 0.450088 0.450088)
			(layers "F.Cu" "F.Mask" "F.Paste")
			(net "GND")
		)
		(pad "V11" smd circle
			(at -25.230074 -23.040086 180)
			(size 0.450088 0.450088)
			(layers "F.Cu" "F.Mask" "F.Paste")
			(net "M_L_CPU0_SA_DQ<17>")
		)
		(pad "V12" smd circle
			(at -24.29002 -23.040086 180)
			(size 0.450088 0.450088)
			(layers "F.Cu" "F.Mask" "F.Paste")
			(net "GND")
		)
		(pad "V13" smd circle
			(at -23.349966 -23.040086 180)
			(size 0.450088 0.450088)
			(layers "F.Cu" "F.Mask" "F.Paste")
			(net "M_H_CPU0_SA_DQ<18>")
		)
		(pad "V14" smd circle
			(at -22.409912 -23.040086 180)
			(size 0.450088 0.450088)
			(layers "F.Cu" "F.Mask" "F.Paste")
			(net "M_H_CPU0_SA_DQ<17>")
		)
		(pad "V15" smd circle
			(at -21.470112 -23.040086 180)
			(size 0.450088 0.450088)
			(layers "F.Cu" "F.Mask" "F.Paste")
			(net "GND")
		)
		(pad "V16" smd circle
			(at -20.530058 -23.040086 180)
			(size 0.450088 0.450088)
			(layers "F.Cu" "F.Mask" "F.Paste")
			(net "M_J_CPU0_SA_DQ<18>")
		)
		(pad "V17" smd circle
			(at -19.590004 -23.040086 180)
			(size 0.450088 0.450088)
			(layers "F.Cu" "F.Mask" "F.Paste")
			(net "GND")
		)
		(pad "V18" smd circle
			(at -18.64995 -23.040086 180)
			(size 0.450088 0.450088)
			(layers "F.Cu" "F.Mask" "F.Paste")
			(net "M_J_CPU0_SA_DQ<17>")
		)
		(pad "V19" smd circle
			(at -17.709896 -23.040086 180)
			(size 0.450088 0.450088)
			(layers "F.Cu" "F.Mask" "F.Paste")
			(net "GND")
		)
		(pad "V20" smd circle
			(at -16.770096 -23.040086 180)
			(size 0.450088 0.450088)
			(layers "F.Cu" "F.Mask" "F.Paste")
			(net "M_I_CPU0_SA_DQ<18>")
		)
		(pad "V21" smd circle
			(at -15.830042 -23.040086 180)
			(size 0.450088 0.450088)
			(layers "F.Cu" "F.Mask" "F.Paste")
			(net "M_I_CPU0_SA_DQ<17>")
		)
		(pad "V22" smd circle
			(at -14.889988 -23.040086 180)
			(size 0.450088 0.450088)
			(layers "F.Cu" "F.Mask" "F.Paste")
			(net "PVDDCR_SOC_P0")
		)
		(pad "V23" smd circle
			(at -13.949934 -23.040086 180)
			(size 0.450088 0.450088)
			(layers "F.Cu" "F.Mask" "F.Paste")
			(net "GND")
		)
		(pad "V24" smd circle
			(at -13.00988 -23.040086 180)
			(size 0.450088 0.450088)
			(layers "F.Cu" "F.Mask" "F.Paste")
			(net "GND")
		)
		(pad "V25" smd circle
			(at -12.07008 -23.040086 180)
			(size 0.450088 0.450088)
			(layers "F.Cu" "F.Mask" "F.Paste")
			(net "GND")
		)
		(pad "V26" smd circle
			(at -11.130026 -23.040086 180)
			(size 0.450088 0.450088)
			(layers "F.Cu" "F.Mask" "F.Paste")
			(net "GND")
		)
		(pad "V27" smd circle
			(at -10.189972 -23.040086 180)
			(size 0.450088 0.450088)
			(layers "F.Cu" "F.Mask" "F.Paste")
			(net "GND")
		)
		(pad "V28" smd circle
			(at -9.249918 -23.040086 180)
			(size 0.450088 0.450088)
			(layers "F.Cu" "F.Mask" "F.Paste")
			(net "GND")
		)
		(pad "V29" smd circle
			(at -8.310118 -23.040086 180)
			(size 0.450088 0.450088)
			(layers "F.Cu" "F.Mask" "F.Paste")
			(net "GND")
		)
		(pad "V30" smd circle
			(at -7.370064 -23.040086 180)
			(size 0.450088 0.450088)
			(layers "F.Cu" "F.Mask" "F.Paste")
			(net "GND")
		)
		(pad "V31" smd circle
			(at -6.43001 -23.040086 180)
			(size 0.450088 0.450088)
			(layers "F.Cu" "F.Mask" "F.Paste")
			(net "GND")
		)
		(pad "V32" smd circle
			(at -5.489956 -23.040086 180)
			(size 0.450088 0.450088)
			(layers "F.Cu" "F.Mask" "F.Paste")
			(net "GND")
		)
		(pad "V33" smd circle
			(at -4.549902 -23.040086 180)
			(size 0.450088 0.450088)
			(layers "F.Cu" "F.Mask" "F.Paste")
			(net "GND")
		)
		(pad "V34" smd circle
			(at -3.610102 -23.040086 180)
			(size 0.450088 0.450088)
			(layers "F.Cu" "F.Mask" "F.Paste")
			(net "GND")
		)
		(pad "V35" smd circle
			(at -2.670048 -23.040086 180)
			(size 0.450088 0.450088)
			(layers "F.Cu" "F.Mask" "F.Paste")
			(net "P5E_CPU0_G3_TX_DP<15>")
		)
		(pad "V36" smd circle
			(at -1.729994 -23.040086 180)
			(size 0.450088 0.450088)
			(layers "F.Cu" "F.Mask" "F.Paste")
			(net "P5E_CPU0_G3_TX_DN<15>")
		)
		(pad "V37" smd circle
			(at -0.78994 -23.040086 180)
			(size 0.450088 0.450088)
			(layers "F.Cu" "F.Mask" "F.Paste")
			(net "GND")
		)
		(pad "V39" smd circle
			(at 1.089914 -23.040086 180)
			(size 0.450088 0.450088)
			(layers "F.Cu" "F.Mask" "F.Paste")
			(net "GND")
		)
		(pad "V40" smd circle
			(at 2.029968 -23.040086 180)
			(size 0.450088 0.450088)
			(layers "F.Cu" "F.Mask" "F.Paste")
			(net "GMI_CPU1_G3_CPU0_G1_TX_DN<0>")
		)
		(pad "V41" smd circle
			(at 2.970022 -23.040086 180)
			(size 0.450088 0.450088)
			(layers "F.Cu" "F.Mask" "F.Paste")
			(net "GMI_CPU1_G3_CPU0_G1_TX_DP<0>")
		)
		(pad "V42" smd circle
			(at 3.910076 -23.040086 180)
			(size 0.450088 0.450088)
			(layers "F.Cu" "F.Mask" "F.Paste")
			(net "GND")
		)
		(pad "V43" smd circle
			(at 4.849876 -23.040086 180)
			(size 0.450088 0.450088)
			(layers "F.Cu" "F.Mask" "F.Paste")
			(net "GND")
		)
		(pad "V44" smd circle
			(at 5.78993 -23.040086 180)
			(size 0.450088 0.450088)
			(layers "F.Cu" "F.Mask" "F.Paste")
			(net "GND")
		)
		(pad "V45" smd circle
			(at 6.729984 -23.040086 180)
			(size 0.450088 0.450088)
			(layers "F.Cu" "F.Mask" "F.Paste")
			(net "GND")
		)
		(pad "V46" smd circle
			(at 7.670038 -23.040086 180)
			(size 0.450088 0.450088)
			(layers "F.Cu" "F.Mask" "F.Paste")
			(net "GND")
		)
		(pad "V47" smd circle
			(at 8.610092 -23.040086 180)
			(size 0.450088 0.450088)
			(layers "F.Cu" "F.Mask" "F.Paste")
			(net "GND")
		)
		(pad "V48" smd circle
			(at 9.549892 -23.040086 180)
			(size 0.450088 0.450088)
			(layers "F.Cu" "F.Mask" "F.Paste")
			(net "GND")
		)
		(pad "V49" smd circle
			(at 10.489946 -23.040086 180)
			(size 0.450088 0.450088)
			(layers "F.Cu" "F.Mask" "F.Paste")
			(net "GND")
		)
		(pad "V50" smd circle
			(at 11.43 -23.040086 180)
			(size 0.450088 0.450088)
			(layers "F.Cu" "F.Mask" "F.Paste")
			(net "GND")
		)
		(pad "V51" smd circle
			(at 12.370054 -23.040086 180)
			(size 0.450088 0.450088)
			(layers "F.Cu" "F.Mask" "F.Paste")
			(net "GND")
		)
		(pad "V52" smd circle
			(at 13.310108 -23.040086 180)
			(size 0.450088 0.450088)
			(layers "F.Cu" "F.Mask" "F.Paste")
			(net "GND")
		)
		(pad "V53" smd circle
			(at 14.249908 -23.040086 180)
			(size 0.450088 0.450088)
			(layers "F.Cu" "F.Mask" "F.Paste")
			(net "GND")
		)
		(pad "V54" smd circle
			(at 15.189962 -23.040086 180)
			(size 0.450088 0.450088)
			(layers "F.Cu" "F.Mask" "F.Paste")
			(net "PVDDIO_P0")
		)
		(pad "V55" smd circle
			(at 16.130016 -23.040086 180)
			(size 0.450088 0.450088)
			(layers "F.Cu" "F.Mask" "F.Paste")
			(net "M_C_CPU0_SA_DQ<17>")
		)
		(pad "V56" smd circle
			(at 17.07007 -23.040086 180)
			(size 0.450088 0.450088)
			(layers "F.Cu" "F.Mask" "F.Paste")
			(net "M_C_CPU0_SA_DQ<18>")
		)
		(pad "V57" smd circle
			(at 18.010124 -23.040086 180)
			(size 0.450088 0.450088)
			(layers "F.Cu" "F.Mask" "F.Paste")
			(net "GND")
		)
		(pad "V58" smd circle
			(at 18.949924 -23.040086 180)
			(size 0.450088 0.450088)
			(layers "F.Cu" "F.Mask" "F.Paste")
			(net "M_D_CPU0_SA_DQ<17>")
		)
		(pad "V59" smd circle
			(at 19.889978 -23.040086 180)
			(size 0.450088 0.450088)
			(layers "F.Cu" "F.Mask" "F.Paste")
			(net "GND")
		)
		(pad "V60" smd circle
			(at 20.830032 -23.040086 180)
			(size 0.450088 0.450088)
			(layers "F.Cu" "F.Mask" "F.Paste")
			(net "M_D_CPU0_SA_DQ<18>")
		)
		(pad "V61" smd circle
			(at 21.770086 -23.040086 180)
			(size 0.450088 0.450088)
			(layers "F.Cu" "F.Mask" "F.Paste")
			(net "GND")
		)
		(pad "V62" smd circle
			(at 22.709886 -23.040086 180)
			(size 0.450088 0.450088)
			(layers "F.Cu" "F.Mask" "F.Paste")
			(net "M_B_CPU0_SA_DQ<17>")
		)
		(pad "V63" smd circle
			(at 23.64994 -23.040086 180)
			(size 0.450088 0.450088)
			(layers "F.Cu" "F.Mask" "F.Paste")
			(net "M_B_CPU0_SA_DQ<18>")
		)
		(pad "V64" smd circle
			(at 24.589994 -23.040086 180)
			(size 0.450088 0.450088)
			(layers "F.Cu" "F.Mask" "F.Paste")
			(net "GND")
		)
		(pad "V65" smd circle
			(at 25.530048 -23.040086 180)
			(size 0.450088 0.450088)
			(layers "F.Cu" "F.Mask" "F.Paste")
			(net "M_F_CPU0_SA_DQ<17>")
		)
		(pad "V66" smd circle
			(at 26.470102 -23.040086 180)
			(size 0.450088 0.450088)
			(layers "F.Cu" "F.Mask" "F.Paste")
			(net "GND")
		)
		(pad "V67" smd circle
			(at 27.409902 -23.040086 180)
			(size 0.450088 0.450088)
			(layers "F.Cu" "F.Mask" "F.Paste")
			(net "M_F_CPU0_SA_DQ<18>")
		)
		(pad "V68" smd circle
			(at 28.349956 -23.040086 180)
			(size 0.450088 0.450088)
			(layers "F.Cu" "F.Mask" "F.Paste")
			(net "GND")
		)
		(pad "V69" smd circle
			(at 29.29001 -23.040086 180)
			(size 0.450088 0.450088)
			(layers "F.Cu" "F.Mask" "F.Paste")
			(net "M_E_CPU0_SA_DQ<17>")
		)
		(pad "V70" smd circle
			(at 30.230064 -23.040086 180)
			(size 0.450088 0.450088)
			(layers "F.Cu" "F.Mask" "F.Paste")
			(net "M_E_CPU0_SA_DQ<18>")
		)
		(pad "V71" smd circle
			(at 31.170118 -23.040086 180)
			(size 0.450088 0.450088)
			(layers "F.Cu" "F.Mask" "F.Paste")
			(net "GND")
		)
		(pad "V72" smd circle
			(at 32.109918 -23.040086 180)
			(size 0.450088 0.450088)
			(layers "F.Cu" "F.Mask" "F.Paste")
			(net "M_A_CPU0_SA_DQ<17>")
		)
		(pad "V73" smd circle
			(at 33.049972 -23.040086 180)
			(size 0.450088 0.450088)
			(layers "F.Cu" "F.Mask" "F.Paste")
			(net "GND")
		)
		(pad "V74" smd circle
			(at 33.990026 -23.040086 180)
			(size 0.450088 0.450088)
			(layers "F.Cu" "F.Mask" "F.Paste")
			(net "M_A_CPU0_SA_DQ<18>")
		)
		(pad "W1" smd circle
			(at -34.159952 -22.23008 180)
			(size 0.450088 0.450088)
			(layers "F.Cu" "F.Mask" "F.Paste")
			(net "GND")
		)
		(pad "W2" smd circle
			(at -33.219898 -22.23008 180)
			(size 0.450088 0.450088)
			(layers "F.Cu" "F.Mask" "F.Paste")
			(net "M_G_CPU0_SA_DQS_DP<2>")
		)
		(pad "W3" smd circle
			(at -32.280098 -22.23008 180)
			(size 0.450088 0.450088)
			(layers "F.Cu" "F.Mask" "F.Paste")
			(net "M_G_CPU0_SA_DQ<19>")
		)
		(pad "W4" smd circle
			(at -31.340044 -22.23008 180)
			(size 0.450088 0.450088)
			(layers "F.Cu" "F.Mask" "F.Paste")
			(net "GND")
		)
		(pad "W5" smd circle
			(at -30.39999 -22.23008 180)
			(size 0.450088 0.450088)
			(layers "F.Cu" "F.Mask" "F.Paste")
			(net "M_K_CPU0_SA_DQS_DP<2>")
		)
		(pad "W6" smd circle
			(at -29.459936 -22.23008 180)
			(size 0.450088 0.450088)
			(layers "F.Cu" "F.Mask" "F.Paste")
			(net "GND")
		)
		(pad "W7" smd circle
			(at -28.519882 -22.23008 180)
			(size 0.450088 0.450088)
			(layers "F.Cu" "F.Mask" "F.Paste")
			(net "M_K_CPU0_SA_DQ<19>")
		)
		(pad "W8" smd circle
			(at -27.580082 -22.23008 180)
			(size 0.450088 0.450088)
			(layers "F.Cu" "F.Mask" "F.Paste")
			(net "GND")
		)
		(pad "W9" smd circle
			(at -26.640028 -22.23008 180)
			(size 0.450088 0.450088)
			(layers "F.Cu" "F.Mask" "F.Paste")
			(net "M_L_CPU0_SA_DQS_DP<2>")
		)
		(pad "W10" smd circle
			(at -25.699974 -22.23008 180)
			(size 0.450088 0.450088)
			(layers "F.Cu" "F.Mask" "F.Paste")
			(net "M_L_CPU0_SA_DQ<19>")
		)
		(pad "W11" smd circle
			(at -24.75992 -22.23008 180)
			(size 0.450088 0.450088)
			(layers "F.Cu" "F.Mask" "F.Paste")
			(net "GND")
		)
		(pad "W12" smd circle
			(at -23.82012 -22.23008 180)
			(size 0.450088 0.450088)
			(layers "F.Cu" "F.Mask" "F.Paste")
			(net "M_H_CPU0_SA_DQS_DP<2>")
		)
		(pad "W13" smd circle
			(at -22.880066 -22.23008 180)
			(size 0.450088 0.450088)
			(layers "F.Cu" "F.Mask" "F.Paste")
			(net "GND")
		)
		(pad "W14" smd circle
			(at -21.940012 -22.23008 180)
			(size 0.450088 0.450088)
			(layers "F.Cu" "F.Mask" "F.Paste")
			(net "M_H_CPU0_SA_DQ<19>")
		)
		(pad "W15" smd circle
			(at -20.999958 -22.23008 180)
			(size 0.450088 0.450088)
			(layers "F.Cu" "F.Mask" "F.Paste")
			(net "GND")
		)
		(pad "W16" smd circle
			(at -20.059904 -22.23008 180)
			(size 0.450088 0.450088)
			(layers "F.Cu" "F.Mask" "F.Paste")
			(net "M_J_CPU0_SA_DQS_DP<2>")
		)
		(pad "W17" smd circle
			(at -19.120104 -22.23008 180)
			(size 0.450088 0.450088)
			(layers "F.Cu" "F.Mask" "F.Paste")
			(net "M_J_CPU0_SA_DQ<19>")
		)
		(pad "W18" smd circle
			(at -18.18005 -22.23008 180)
			(size 0.450088 0.450088)
			(layers "F.Cu" "F.Mask" "F.Paste")
			(net "GND")
		)
		(pad "W19" smd circle
			(at -17.239996 -22.23008 180)
			(size 0.450088 0.450088)
			(layers "F.Cu" "F.Mask" "F.Paste")
			(net "M_I_CPU0_SA_DQS_DP<2>")
		)
		(pad "W20" smd circle
			(at -16.299942 -22.23008 180)
			(size 0.450088 0.450088)
			(layers "F.Cu" "F.Mask" "F.Paste")
			(net "GND")
		)
		(pad "W21" smd circle
			(at -15.359888 -22.23008 180)
			(size 0.450088 0.450088)
			(layers "F.Cu" "F.Mask" "F.Paste")
			(net "M_I_CPU0_SA_DQ<19>")
		)
		(pad "W22" smd circle
			(at -14.420088 -22.23008 180)
			(size 0.450088 0.450088)
			(layers "F.Cu" "F.Mask" "F.Paste")
			(net "GND")
		)
		(pad "W23" smd circle
			(at -13.480034 -22.23008 180)
			(size 0.450088 0.450088)
			(layers "F.Cu" "F.Mask" "F.Paste")
			(net "P5E_CPU0_G3_TX_DP<2>")
		)
		(pad "W24" smd circle
			(at -12.53998 -22.23008 180)
			(size 0.450088 0.450088)
			(layers "F.Cu" "F.Mask" "F.Paste")
			(net "P5E_CPU0_G3_TX_DN<2>")
		)
		(pad "W25" smd circle
			(at -11.599926 -22.23008 180)
			(size 0.450088 0.450088)
			(layers "F.Cu" "F.Mask" "F.Paste")
			(net "GND")
		)
		(pad "W26" smd circle
			(at -10.659872 -22.23008 180)
			(size 0.450088 0.450088)
			(layers "F.Cu" "F.Mask" "F.Paste")
			(net "P5E_CPU0_G3_TX_DP<6>")
		)
		(pad "W27" smd circle
			(at -9.720072 -22.23008 180)
			(size 0.450088 0.450088)
			(layers "F.Cu" "F.Mask" "F.Paste")
			(net "P5E_CPU0_G3_TX_DN<6>")
		)
		(pad "W28" smd circle
			(at -8.780018 -22.23008 180)
			(size 0.450088 0.450088)
			(layers "F.Cu" "F.Mask" "F.Paste")
			(net "GND")
		)
		(pad "W29" smd circle
			(at -7.839964 -22.23008 180)
			(size 0.450088 0.450088)
			(layers "F.Cu" "F.Mask" "F.Paste")
			(net "PVDDCR_CPU0_P0")
		)
		(pad "W30" smd circle
			(at -6.89991 -22.23008 180)
			(size 0.450088 0.450088)
			(layers "F.Cu" "F.Mask" "F.Paste")
			(net "PVDDCR_CPU0_P0")
		)
		(pad "W31" smd circle
			(at -5.96011 -22.23008 180)
			(size 0.450088 0.450088)
			(layers "F.Cu" "F.Mask" "F.Paste")
			(net "TP_CPU0_TEST41_IDO")
		)
		(pad "W32" smd circle
			(at -5.020056 -22.23008 180)
			(size 0.450088 0.450088)
			(layers "F.Cu" "F.Mask" "F.Paste")
			(net "PVDDCR_CPU0_P0")
		)
		(pad "W33" smd circle
			(at -4.080002 -22.23008 180)
			(size 0.450088 0.450088)
			(layers "F.Cu" "F.Mask" "F.Paste")
			(net "PVDDCR_CPU0_P0")
		)
		(pad "W34" smd circle
			(at -3.139948 -22.23008 180)
			(size 0.450088 0.450088)
			(layers "F.Cu" "F.Mask" "F.Paste")
			(net "GND")
		)
		(pad "W35" smd circle
			(at -2.199894 -22.23008 180)
			(size 0.450088 0.450088)
			(layers "F.Cu" "F.Mask" "F.Paste")
			(net "GND")
		)
		(pad "W36" smd circle
			(at -1.260094 -22.23008 180)
			(size 0.450088 0.450088)
			(layers "F.Cu" "F.Mask" "F.Paste")
			(net "GND")
		)
		(pad "W40" smd circle
			(at 1.560068 -22.23008 180)
			(size 0.450088 0.450088)
			(layers "F.Cu" "F.Mask" "F.Paste")
			(net "GND")
		)
		(pad "W41" smd circle
			(at 2.500122 -22.23008 180)
			(size 0.450088 0.450088)
			(layers "F.Cu" "F.Mask" "F.Paste")
			(net "GND")
		)
		(pad "W42" smd circle
			(at 3.439922 -22.23008 180)
			(size 0.450088 0.450088)
			(layers "F.Cu" "F.Mask" "F.Paste")
			(net "GND")
		)
		(pad "W43" smd circle
			(at 4.379976 -22.23008 180)
			(size 0.450088 0.450088)
			(layers "F.Cu" "F.Mask" "F.Paste")
			(net "PVDDCR_CPU0_P0")
		)
	)
)
